FILE_TYPE = CONNECTIVITY;
{Allegro Design Entry HDL 17.2-2016 S081 (4005846) 1/11/2022}
"PAGE_NUMBER" = 43;
0"NC";
END.
